# T6G (Grand Teton) — schematic netlist excerpt (pin names and nets, part order shuffled) for the footprints in the layout excerpt that follows; sources: Cadence DE-HDL packaged netlist, KiCad conversion of 04192023_DAF0TMB3IC0_F0TG_MB_C_brd_V02_OCP.brd

PU12  RAA229620GNPHA0  RAA229620GNP#HA0 IC  pkg QFN48_TH_0-4_6X6XH  page 200
  PWM0  = PVDDIO_P0_PWM1
  PWM1  = PVDDIO_P0_PWM2
  PWM2  = PVDDIO_P0_PWM3
  PWM3  = PVDDIO_P0_PWM4
  PWM4  = NC_PVDDCR_CPU1_P0_PWM8
  PWM5  = NC_PVDDCR_CPU1_P0_PWM7
  PWM6  = PVDDCR_CPU1_P0_PWM6
  PWM7  = PVDDCR_CPU1_P0_PWM5
  PWM8  = PVDDCR_CPU1_P0_PWM4
  PWM9  = PVDDCR_CPU1_P0_PWM3
  PWM10  = PVDDCR_CPU1_P0_PWM2
  PWM11  = PVDDCR_CPU1_P0_PWM1
  PMSDA  = SMB_DIO_PVDDCR_CPU1_P0_R
  PMSCL  = SMB_CLK_PVDDCR_CPU1_P0_R
  NPMALERT  = PVDDCR_CPU1_P0_SMB_ALERT_R
  PG0  = PWRGD_PVDDCR_CPU1_P0_R
  EN0  = PVDDCR_CPU1_P0_EN_R
  RESET_L  = PVDDCR_CPU1_P0_RESET_N_R
  VDDIO  = PVDD18_S5_P0
  PG1  = PWRGD_PVDDIO_P0_R
  SVD  = SVID_PVDDCR_CPU1_P0_SVD_R1
  SVC  = SVID_PVDDCR_CPU1_P0_SVC_R1
  SVTO  = SVID_PVDDCR_CPU1_P0_SVTO_R
  SVTI  = SVID_PVDDCR_CPU1_P0_SVTI_R
  VSEN0  = VSENSE_PVDDCR_CPU1_P0_VSEN0
  RGND0  = VSENSE_VSS_SENSE_C_P0
  CS11  = PVDDCR_CPU1_P0_IMON1
  CS10  = PVDDCR_CPU1_P0_IMON2
  CS9  = PVDDCR_CPU1_P0_IMON3
  CS8  = PVDDCR_CPU1_P0_IMON4
  CS7  = PVDDCR_CPU1_P0_IMON5
  CS6  = PVDDCR_CPU1_P0_IMON6
  CS5  = NC_PVDDCR_CPU1_P0_IMON7
  CS4  = NC_PVDDCR_CPU1_P0_IMON8
  CS3  = PVDDIO_P0_IMON4
  CS2  = PVDDIO_P0_IMON3
  CS1  = PVDDIO_P0_IMON2
  CS0  = PVDDIO_P0_IMON1
  RGND1  = VSENSE_VSS_SENSE_B_P0
  VSEN1  = VSENSE_PVDDIO_P0_VSEN1
  OCP_L  = PVDDCR_CPU1_P0_OCP_N_R
  \en1||addr_cfg\  = PVDDCR_CPU1_P0_EN1_ADDR_CFG
  TEMP1  = PVDDIO_P0_TEMP1
  TEMP0  = PVDDCR_CPU1_P0_TEMP0
  \vmon||iinsen\  = PVDDCR_CPU1_P0_VMON
  VINSEN  = PVDDCR_CPU1_P0_VINSEN
  VCC  = PVDDCR_CPU1_P0_VCC
  VCCS  = PVDDCR_CPU1_P0_VCCS
  TH_GND  = GND

(kicad_pcb
	(version 20260206)
	(generator "pcbnew")
	(generator_version "10.0")
	(general
		(thickness 1.6)
		(legacy_teardrops no)
	)
	(paper "A4")
	(title_block
		(title "04192023_DAF0TMB3IC0_F0TG_MB_C_brd_V02_OCP.brd")
		(comment 1 "Grand Teton / footprint 4890 of 8354 (PU12), pads 43-49 of 49")
	)
	(layers
		(0 "F.Cu" signal "TOP")
		(4 "In1.Cu" signal "GND")
		(6 "In2.Cu" signal "IN1")
		(8 "In3.Cu" signal "GND1")
		(10 "In4.Cu" signal "IN2")
		(12 "In5.Cu" signal "GND2")
		(14 "In6.Cu" signal "IN3")
		(16 "In7.Cu" signal "GND3")
		(18 "In8.Cu" signal "VCC")
		(20 "In9.Cu" signal "VCC1")
		(22 "In10.Cu" signal "GND4")
		(24 "In11.Cu" signal "IN4")
		(26 "In12.Cu" signal "GND5")
		(28 "In13.Cu" signal "IN5")
		(30 "In14.Cu" signal "GND6")
		(32 "In15.Cu" signal "IN6")
		(34 "In16.Cu" signal "GND7")
		(2 "B.Cu" signal "BOTTOM")
		(9 "F.Adhes" user "F.Adhesive")
		(11 "B.Adhes" user "B.Adhesive")
		(13 "F.Paste" user "Package Geometry/Pastemask Top")
		(15 "B.Paste" user "Package Geometry/Pastemask Bottom")
		(5 "F.SilkS" user "Ref Des/Silkscreen Top")
		(7 "B.SilkS" user "Ref Des/Silkscreen Bottom")
		(1 "F.Mask" user "Board Geometry/Soldermask Top")
		(3 "B.Mask" user "Board Geometry/Soldermask Bottom")
		(17 "Dwgs.User" user "User.Drawings")
		(19 "Cmts.User" user "User.Comments")
		(21 "Eco1.User" user "User.Eco1")
		(23 "Eco2.User" user "User.Eco2")
		(25 "Edge.Cuts" user "Board Geometry/Outline")
		(27 "Margin" user)
		(31 "F.CrtYd" user "Package Geometry/Place Bound Top")
		(29 "B.CrtYd" user "Package Geometry/Place Bound Bottom")
		(35 "F.Fab" user "Ref Des/Assembly Top")
		(33 "B.Fab" user "Ref Des/Assembly Bottom")
	)
	(footprint ""
		(layer "F.Cu")
		(at 310.134 -360.68 -90)
		(property "Reference" "PU12"
			(at -6.05409 1.856232 0)
			(unlocked yes)
			(layer "F.SilkS")
			(effects
				(font
					(size 0.7874 0.5842)
					(thickness 0.1524)
				)
			)
		)
		(property "Value" ""
			(at 0 0 270)
			(layer "F.Fab")
			(effects
				(font
					(size 1.27 1.27)
				)
			)
		)
		(duplicate_pad_numbers_are_jumpers no)
		(pad "43" smd rect
			(at -0.199898 -2.875026 270)
			(size 0.1778 0.6604)
			(layers "F.Cu" "F.Mask" "F.Paste")
			(net "PVDDIO_P0_TEMP1")
		)
		(pad "44" smd rect
			(at -0.599948 -2.875026 270)
			(size 0.1778 0.6604)
			(layers "F.Cu" "F.Mask" "F.Paste")
			(net "PVDDCR_CPU1_P0_TEMP0")
		)
		(pad "45" smd rect
			(at -0.999998 -2.875026 270)
			(size 0.1778 0.6604)
			(layers "F.Cu" "F.Mask" "F.Paste")
			(net "PVDDCR_CPU1_P0_VMON")
		)
		(pad "46" smd rect
			(at -1.400048 -2.875026 270)
			(size 0.1778 0.6604)
			(layers "F.Cu" "F.Mask" "F.Paste")
			(net "PVDDCR_CPU1_P0_VINSEN")
		)
		(pad "47" smd rect
			(at -1.800098 -2.875026 270)
			(size 0.1778 0.6604)
			(layers "F.Cu" "F.Mask" "F.Paste")
			(net "PVDDCR_CPU1_P0_VCC")
		)
		(pad "48" smd rect
			(at -2.199894 -2.875026 270)
			(size 0.1778 0.6604)
			(layers "F.Cu" "F.Mask" "F.Paste")
			(net "PVDDCR_CPU1_P0_VCCS")
		)
		(pad "TH" smd rect
			(at 0 0 270)
			(size 4.4196 4.4196)
			(layers "F.Cu" "F.Mask" "F.Paste")
			(net "GND")
		)
	)
)
